#ISCELL
  mstr_misc dns *
  *
#ISCELL
  mstr_symbols design_note *
  *
#ISCELL
  mstr_symbols intel_corp_bpage *
  *
#CELL
  mstr_discrete res *
  page214_i101
#ISCELL
  mstr_symbols gnd *
  page214_i102
#ISCELL
  mstr_standard offpage *
  page214_i103
#CELL
  mstr_discrete res *
  page214_i105
#ISCELL
  mstr_standard offpage *
  page214_i106
#ISCELL
  mstr_symbols pvccio_cpu1 *
  page214_i107
#CELL
  dev_discrete cap_a *
  page214_i108
#CELL
  mstr_discrete res *
  page214_i109
#CELL
  mstr_discrete ir354xx *
  page214_i126
#CELL
  mstr_discrete res *
  page214_i127
#ISCELL
  mstr_symbols gnd *
  page214_i128
#CELL
  mstr_misc shunt *
  page214_i129
#CELL
  mstr_misc shunt *
  page214_i130
#ISCELL
  mstr_symbols gnd *
  page214_i133
#CELL
  mstr_discrete cap *
  page214_i134
#ISCELL
  mstr_symbols gnd *
  page214_i135
#ISCELL
  mstr_symbols gnd *
  page214_i136
#CELL
  dev_discrete cap_a *
  page214_i137
#CELL
  mstr_discrete cap *
  page214_i143
#CELL
  mstr_discrete res *
  page214_i145
#CELL
  w_hdl sc22u16v5mx-4-gp *
  page214_i148
#CELL
  w_hdl sc22u16v5mx-4-gp *
  page214_i149
#ISCELL
  mstr_symbols gnd *
  page214_i150
#ISCELL
  mstr_symbols gnd *
  page214_i151
#CELL
  w_hdl sc22u16v5mx-4-gp *
  page214_i152
#ISCELL
  mstr_symbols gnd *
  page214_i153
#CELL
  w_hdl sc22u16v5mx-4-gp *
  page214_i154
#ISCELL
  mstr_symbols gnd *
  page214_i155
#CELL
  w_hdl sc22u16v5mx-4-gp *
  page214_i156
#ISCELL
  mstr_symbols gnd *
  page214_i157
#CELL
  w_hdl sc22u16v5mx-4-gp *
  page214_i158
#ISCELL
  mstr_symbols gnd *
  page214_i159
#CELL
  w_hdl sc22u16v5mx-4-gp *
  page214_i160
#CELL
  w_hdl sc22u16v5mx-4-gp *
  page214_i161
#ISCELL
  mstr_symbols gnd *
  page214_i162
#ISCELL
  mstr_symbols gnd *
  page214_i163
#CELL
  w_hdl sc22u16v5mx-4-gp *
  page214_i164
#ISCELL
  mstr_symbols gnd *
  page214_i165
#CELL
  w_hdl sc22u16v5mx-4-gp *
  page214_i166
#ISCELL
  mstr_symbols gnd *
  page214_i167
#CELL
  w_hdl sc22u16v5mx-4-gp *
  page214_i168
#CELL
  w_hdl sc22u16v5mx-4-gp *
  page214_i169
#ISCELL
  mstr_symbols gnd *
  page214_i170
#ISCELL
  mstr_symbols gnd *
  page214_i171
#ISCELL
  mstr_symbols universal_power *
  page214_i172
#CELL
  mstr_discrete res *
  page214_i173
#CELL
  w_hdl ind-150nh-56-gp *
  page214_i174
#CELL
  w_hdl sc1u10v2kx-4-gp *
  page214_i175
#CELL
  w_hdl 1r3f-gp *
  page214_i176
#CELL
  mstr_discrete capp *
  page214_i177
#CELL
  mstr_discrete capp *
  page214_i178
#CELL
  mstr_discrete capp *
  page214_i24
#ISCELL
  mstr_symbols pvccio_cpu1 *
  page214_i3
#ISCELL
  mstr_standard offpage *
  page214_i58
#ISCELL
  mstr_standard offpage *
  page214_i59
#ISCELL
  mstr_symbols gnd *
  page214_i6
#ISCELL
  mstr_standard offpage *
  page214_i60
#ISCELL
  mstr_symbols pvccio_cpu1 *
  page214_i64
#CELL
  dev_discrete cap_a *
  page214_i65
#ISCELL
  mstr_symbols gnd *
  page214_i66
#ISCELL
  mstr_symbols gnd *
  page214_i68
#CELL
  mstr_discrete cap *
  page214_i73
#CELL
  mstr_discrete cap *
  page214_i76
#CELL
  dev_discrete cap_a *
  page214_i77
#CELL
  mstr_discrete cap *
  page214_i78
#CELL
  mstr_discrete cap *
  page214_i79
#CELL
  mstr_discrete cap *
  page214_i80
#CELL
  mstr_discrete cap *
  page214_i81
#ISCELL
  mstr_standard offpage *
  page214_i82
#CELL
  mstr_discrete cap *
  page214_i83
#ISCELL
  mstr_symbols gnd *
  page214_i84
#ISCELL
  mstr_symbols p5v_stby *
  page214_i88
#ISCELL
  mstr_symbols universal_power *
  page214_i89
#ISCELL
  mstr_standard offpage *
  page214_i95
#CELL
  dev_discrete cap_a *
  page214_i96
#ISCELL
  mstr_standard offpage *
  page214_i97
